(kicad_pcb
	(version 20241229)
	(generator "pcbnew")
	(generator_version "9.0")
	(general
		(thickness 1.6)
		(legacy_teardrops no)
	)
	(paper "A4")
	(title_block
		(title "environment-sensor")
		(comment 1 "footprints 25-29 of 109")
	)
	(layers
		(0 "F.Cu" signal)
		(4 "In1.Cu" signal)
		(6 "In2.Cu" signal)
		(2 "B.Cu" signal)
		(9 "F.Adhes" user "F.Adhesive")
		(11 "B.Adhes" user "B.Adhesive")
		(13 "F.Paste" user)
		(15 "B.Paste" user)
		(5 "F.SilkS" user "F.Silkscreen")
		(7 "B.SilkS" user "B.Silkscreen")
		(1 "F.Mask" user)
		(3 "B.Mask" user)
		(17 "Dwgs.User" user "User.Drawings")
		(19 "Cmts.User" user "User.Comments")
		(21 "Eco1.User" user "User.Eco1")
		(23 "Eco2.User" user "User.Eco2")
		(25 "Edge.Cuts" user)
		(27 "Margin" user)
		(31 "F.CrtYd" user "F.Courtyard")
		(29 "B.CrtYd" user "B.Courtyard")
		(35 "F.Fab" user)
		(33 "B.Fab" user)
	)
	(footprint "antmicro-footprints:R_0402_1005Metric"
		(layer "F.Cu")
		(at 185.15 138.4 90)
		(descr "Resistor SMD 0402")
		(tags "resistor SMD 0402")
		(property "Reference" "R14"
			(at 20.346 -1.2685 270)
			(layer "B.SilkS")
			(effects
				(font
					(size 0.7 0.7)
					(thickness 0.15)
				)
				(justify left bottom mirror)
			)
		)
		(property "Value" "R_0R_0402"
			(at 0 1.4 90)
			(layer "F.Fab")
			(effects
				(font
					(size 0.7 0.7)
					(thickness 0.15)
				)
				(justify left bottom)
			)
		)
		(property "Description" "SMD Chip Resistor, Jumper, 0 ohm, 100 mW, 0402 [1005 Metric], Thick Film, General Purpose"
			(at 0 0 90)
			(layer "F.Fab")
			(hide yes)
			(effects
				(font
					(size 1.27 1.27)
					(thickness 0.15)
				)
			)
		)
		(property "Author" "Antmicro"
			(at 323.55 -46.75 0)
			(layer "F.Fab")
			(hide yes)
			(effects
				(font
					(size 1 1)
					(thickness 0.15)
				)
			)
		)
		(property "Current" "1A"
			(at 323.55 -46.75 0)
			(layer "F.Fab")
			(hide yes)
			(effects
				(font
					(size 1 1)
					(thickness 0.15)
				)
			)
		)
		(property "License" "Apache-2.0"
			(at 323.55 -46.75 0)
			(layer "F.Fab")
			(hide yes)
			(effects
				(font
					(size 1 1)
					(thickness 0.15)
				)
			)
		)
		(property "MPN" "ERJ2GE0R00X"
			(at 323.55 -46.75 0)
			(layer "F.Fab")
			(hide yes)
			(effects
				(font
					(size 1 1)
					(thickness 0.15)
				)
			)
		)
		(property "Manufacturer" "Panasonic"
			(at 323.55 -46.75 0)
			(layer "F.Fab")
			(hide yes)
			(effects
				(font
					(size 1 1)
					(thickness 0.15)
				)
			)
		)
		(property "Public" "False"
			(at 323.55 -46.75 0)
			(layer "F.Fab")
			(hide yes)
			(effects
				(font
					(size 1 1)
					(thickness 0.15)
				)
			)
		)
		(property "Tolerance" ""
			(at 323.55 -46.75 0)
			(layer "F.Fab")
			(hide yes)
			(effects
				(font
					(size 1 1)
					(thickness 0.15)
				)
			)
		)
		(property "Val" "0R"
			(at 323.55 -46.75 0)
			(layer "F.Fab")
			(hide yes)
			(effects
				(font
					(size 1 1)
					(thickness 0.15)
				)
			)
		)
		(sheetfile "environment-sensor.kicad_sch")
		(attr smd)
		(fp_rect
			(start -0.925 -0.47)
			(end 0.925 0.47)
			(stroke
				(width 0.05)
				(type default)
			)
			(fill no)
			(layer "F.CrtYd")
		)
		(fp_rect
			(start -0.5 -0.25)
			(end 0.5 0.25)
			(stroke
				(width 0.15)
				(type solid)
			)
			(fill no)
			(layer "F.Fab")
		)
		(pad "1" smd roundrect
			(at -0.48 0 90)
			(size 0.59 0.64)
			(layers "F.Cu" "F.Mask" "F.Paste")
			(roundrect_rratio 0.25)
			(net 45 "Net-(U1-RXD)")
			(pintype "passive")
		)
		(pad "2" smd roundrect
			(at 0.48 0 90)
			(size 0.59 0.64)
			(layers "F.Cu" "F.Mask" "F.Paste")
			(roundrect_rratio 0.25)
			(net 17 "LPUART_1_STM_TX")
			(pintype "passive")
		)
	)
	(footprint "antmicro-footprints:C_0402_1005Metric"
		(layer "F.Cu")
		(at 187.094 125.087 90)
		(descr "Capacitor SMD 0402")
		(tags "capacitor SMD 0402")
		(property "Reference" "C11"
			(at 6.887 8.006 180)
			(layer "F.SilkS")
			(effects
				(font
					(size 0.7 0.7)
					(thickness 0.15)
				)
				(justify left bottom)
			)
		)
		(property "Value" "C_2u2_0402"
			(at 0 1.4 90)
			(layer "F.Fab")
			(effects
				(font
					(size 0.7 0.7)
					(thickness 0.15)
				)
				(justify left bottom)
			)
		)
		(property "Description" "SMD Multilayer Ceramic Capacitor, 2.2 µF, 10 V, 0402 [1005 Metric], ± 10%, X5R, C"
			(at 0 0 90)
			(layer "F.Fab")
			(hide yes)
			(effects
				(font
					(size 1.27 1.27)
					(thickness 0.15)
				)
			)
		)
		(property "Author" "Antmicro"
			(at 312.181 -62.007 0)
			(layer "F.Fab")
			(hide yes)
			(effects
				(font
					(size 1 1)
					(thickness 0.15)
				)
			)
		)
		(property "Dielectric" ""
			(at 312.181 -62.007 0)
			(layer "F.Fab")
			(hide yes)
			(effects
				(font
					(size 1 1)
					(thickness 0.15)
				)
			)
		)
		(property "License" "Apache-2.0"
			(at 312.181 -62.007 0)
			(layer "F.Fab")
			(hide yes)
			(effects
				(font
					(size 1 1)
					(thickness 0.15)
				)
			)
		)
		(property "MPN" "C1005X5R1A225K050BC"
			(at 312.181 -62.007 0)
			(layer "F.Fab")
			(hide yes)
			(effects
				(font
					(size 1 1)
					(thickness 0.15)
				)
			)
		)
		(property "Manufacturer" "TDK"
			(at 312.181 -62.007 0)
			(layer "F.Fab")
			(hide yes)
			(effects
				(font
					(size 1 1)
					(thickness 0.15)
				)
			)
		)
		(property "Public" "False"
			(at 312.181 -62.007 0)
			(layer "F.Fab")
			(hide yes)
			(effects
				(font
					(size 1 1)
					(thickness 0.15)
				)
			)
		)
		(property "Val" "2u2"
			(at 312.181 -62.007 0)
			(layer "F.Fab")
			(hide yes)
			(effects
				(font
					(size 1 1)
					(thickness 0.15)
				)
			)
		)
		(property "Voltage" ""
			(at 312.181 -62.007 0)
			(layer "F.Fab")
			(hide yes)
			(effects
				(font
					(size 1 1)
					(thickness 0.15)
				)
			)
		)
		(sheetfile "environment-sensor.kicad_sch")
		(attr smd)
		(fp_rect
			(start -0.925 -0.47)
			(end 0.925 0.47)
			(stroke
				(width 0.05)
				(type default)
			)
			(fill no)
			(layer "F.CrtYd")
		)
		(fp_line
			(start 0.504 -0.25)
			(end 0.504 0.248)
			(stroke
				(width 0.15)
				(type solid)
			)
			(layer "F.Fab")
		)
		(fp_line
			(start -0.494 -0.25)
			(end 0.504 -0.25)
			(stroke
				(width 0.15)
				(type solid)
			)
			(layer "F.Fab")
		)
		(fp_line
			(start 0.504 0.248)
			(end -0.494 0.248)
			(stroke
				(width 0.15)
				(type solid)
			)
			(layer "F.Fab")
		)
		(fp_line
			(start -0.494 0.248)
			(end -0.494 -0.25)
			(stroke
				(width 0.15)
				(type solid)
			)
			(layer "F.Fab")
		)
		(pad "1" smd roundrect
			(at -0.48 0 90)
			(size 0.59 0.64)
			(layers "F.Cu" "F.Mask" "F.Paste")
			(roundrect_rratio 0.25)
			(net 2 "+3V3")
			(pintype "passive")
		)
		(pad "2" smd roundrect
			(at 0.48 0 90)
			(size 0.59 0.64)
			(layers "F.Cu" "F.Mask" "F.Paste")
			(roundrect_rratio 0.25)
			(net 1 "GND")
			(pintype "passive")
		)
	)
	(footprint "antmicro-footprints:C_0402_1005Metric"
		(layer "F.Cu")
		(at 182.91 132.6 180)
		(descr "Capacitor SMD 0402")
		(tags "capacitor SMD 0402")
		(property "Reference" "C16"
			(at -3.04 -0.45 0)
			(layer "F.SilkS")
			(effects
				(font
					(size 0.7 0.7)
					(thickness 0.15)
				)
				(justify right bottom)
			)
		)
		(property "Value" "C_16p_0402"
			(at -1.022927 2.155213 0)
			(layer "F.Fab")
			(effects
				(font
					(size 0.7 0.7)
					(thickness 0.15)
				)
				(justify right bottom)
			)
		)
		(property "Description" "SMD Multilayer Ceramic Capacitor, General Purpose, 16 pF, 50 V, 0402 [1005 Metric], ± 5%, C0G / NP0"
			(at 0 0 180)
			(layer "F.Fab")
			(hide yes)
			(effects
				(font
					(size 1.27 1.27)
					(thickness 0.15)
				)
			)
		)
		(property "Author" "Antmicro"
			(at 365.82 265.2 0)
			(layer "F.Fab")
			(hide yes)
			(effects
				(font
					(size 1 1)
					(thickness 0.15)
				)
			)
		)
		(property "Dielectric" ""
			(at 365.82 265.2 0)
			(layer "F.Fab")
			(hide yes)
			(effects
				(font
					(size 1 1)
					(thickness 0.15)
				)
			)
		)
		(property "License" "Apache-2.0"
			(at 365.82 265.2 0)
			(layer "F.Fab")
			(hide yes)
			(effects
				(font
					(size 1 1)
					(thickness 0.15)
				)
			)
		)
		(property "MPN" "0402N160J500CT"
			(at 365.82 265.2 0)
			(layer "F.Fab")
			(hide yes)
			(effects
				(font
					(size 1 1)
					(thickness 0.15)
				)
			)
		)
		(property "Manufacturer" "Walsin"
			(at 365.82 265.2 0)
			(layer "F.Fab")
			(hide yes)
			(effects
				(font
					(size 1 1)
					(thickness 0.15)
				)
			)
		)
		(property "Public" "False"
			(at 365.82 265.2 0)
			(layer "F.Fab")
			(hide yes)
			(effects
				(font
					(size 1 1)
					(thickness 0.15)
				)
			)
		)
		(property "Val" "16p"
			(at 365.82 265.2 0)
			(layer "F.Fab")
			(hide yes)
			(effects
				(font
					(size 1 1)
					(thickness 0.15)
				)
			)
		)
		(property "Voltage" ""
			(at 365.82 265.2 0)
			(layer "F.Fab")
			(hide yes)
			(effects
				(font
					(size 1 1)
					(thickness 0.15)
				)
			)
		)
		(sheetfile "environment-sensor.kicad_sch")
		(attr smd)
		(fp_rect
			(start -0.925 -0.47)
			(end 0.925 0.47)
			(stroke
				(width 0.05)
				(type default)
			)
			(fill no)
			(layer "F.CrtYd")
		)
		(fp_line
			(start 0.504 0.248)
			(end -0.494 0.248)
			(stroke
				(width 0.15)
				(type solid)
			)
			(layer "F.Fab")
		)
		(fp_line
			(start 0.504 -0.25)
			(end 0.504 0.248)
			(stroke
				(width 0.15)
				(type solid)
			)
			(layer "F.Fab")
		)
		(fp_line
			(start -0.494 0.248)
			(end -0.494 -0.25)
			(stroke
				(width 0.15)
				(type solid)
			)
			(layer "F.Fab")
		)
		(fp_line
			(start -0.494 -0.25)
			(end 0.504 -0.25)
			(stroke
				(width 0.15)
				(type solid)
			)
			(layer "F.Fab")
		)
		(pad "1" smd roundrect
			(at -0.48 0 180)
			(size 0.59 0.64)
			(layers "F.Cu" "F.Mask" "F.Paste")
			(roundrect_rratio 0.25)
			(net 87 "/OSC32_OUT")
			(pintype "passive")
		)
		(pad "2" smd roundrect
			(at 0.48 0 180)
			(size 0.59 0.64)
			(layers "F.Cu" "F.Mask" "F.Paste")
			(roundrect_rratio 0.25)
			(net 1 "GND")
			(pintype "passive")
		)
	)
	(footprint "antmicro-footprints:Sensirion_DFN-4-1.5x1.5x0.5mm_P0.8mm"
		(layer "F.Cu")
		(at 207.85 119.685 180)
		(descr "Sensiron's 4-pin 1.5mm x 1.5mm Dual Flat No-Lead, used for SHT4x series I²C Humidity & Temperature Sensors, 0.5mm Height. Based on \"Recommended land pattern\" from SHT4x Datasheet V3: https://sensirion.com/media/documents/33FD6951/624C4357/Datasheet_SHT4x.pdf")
		(tags "dfn4 DFN-4 sensirion sht4x SHT40 SHT41 SHT45")
		(property "Reference" "U5"
			(at -0.45 1.485 0)
			(unlocked yes)
			(layer "F.SilkS")
			(effects
				(font
					(size 0.65 0.65)
					(thickness 0.15)
				)
			)
		)
		(property "Value" "SHT45"
			(at 0 -2.2 180)
			(unlocked yes)
			(layer "F.Fab")
			(effects
				(font
					(size 1 1)
					(thickness 0.15)
				)
			)
		)
		(property "Description" "Sensor"
			(at 0 0 180)
			(layer "F.Fab")
			(hide yes)
			(effects
				(font
					(size 1.27 1.27)
					(thickness 0.15)
				)
			)
		)
		(property "Author" "Antmicro"
			(at 415.7 239.37 0)
			(layer "F.Fab")
			(hide yes)
			(effects
				(font
					(size 1 1)
					(thickness 0.15)
				)
			)
		)
		(property "License" "Apache-2.0"
			(at 415.7 239.37 0)
			(layer "F.Fab")
			(hide yes)
			(effects
				(font
					(size 1 1)
					(thickness 0.15)
				)
			)
		)
		(property "MPN" "SHT45-AD1B-R2"
			(at 415.7 239.37 0)
			(layer "F.Fab")
			(hide yes)
			(effects
				(font
					(size 1 1)
					(thickness 0.15)
				)
			)
		)
		(property "Manufacturer" "Sensirion"
			(at 415.7 239.37 0)
			(layer "F.Fab")
			(hide yes)
			(effects
				(font
					(size 1 1)
					(thickness 0.15)
				)
			)
		)
		(sheetfile "environment-sensor.kicad_sch")
		(attr smd)
		(fp_line
			(start 0.801 0.801)
			(end 0.801 0.699)
			(stroke
				(width 0.15)
				(type solid)
			)
			(layer "F.SilkS")
		)
		(fp_line
			(start 0.801 -0.701)
			(end 0.801 -0.803)
			(stroke
				(width 0.15)
				(type solid)
			)
			(layer "F.SilkS")
		)
		(fp_line
			(start 0.801 -0.803)
			(end -1.2 -0.803)
			(stroke
				(width 0.15)
				(type solid)
			)
			(layer "F.SilkS")
		)
		(fp_line
			(start -0.803 0.801)
			(end 0.801 0.801)
			(stroke
				(width 0.15)
				(type solid)
			)
			(layer "F.SilkS")
		)
		(fp_line
			(start -0.803 0.699)
			(end -0.803 0.801)
			(stroke
				(width 0.15)
				(type solid)
			)
			(layer "F.SilkS")
		)
		(fp_circle
			(center -1.21 -0.41)
			(end -1.162 -0.41)
			(stroke
				(width 0.15)
				(type solid)
			)
			(fill yes)
			(layer "F.SilkS")
		)
		(fp_rect
			(start -1.25 -1.25)
			(end 1.248 1.248)
			(stroke
				(width 0.05)
				(type solid)
			)
			(fill no)
			(layer "F.CrtYd")
		)
		(fp_line
			(start 0.749 0.749)
			(end -0.749 0.749)
			(stroke
				(width 0.15)
				(type solid)
			)
			(layer "F.Fab")
		)
		(fp_line
			(start 0.749 -0.749)
			(end 0.749 0.749)
			(stroke
				(width 0.15)
				(type solid)
			)
			(layer "F.Fab")
		)
		(fp_line
			(start -0.599 -0.749)
			(end 0.749 -0.749)
			(stroke
				(width 0.15)
				(type solid)
			)
			(layer "F.Fab")
		)
		(fp_line
			(start -0.749 0.749)
			(end -0.749 -0.599)
			(stroke
				(width 0.15)
				(type solid)
			)
			(layer "F.Fab")
		)
		(fp_line
			(start -0.749 -0.599)
			(end -0.599 -0.749)
			(stroke
				(width 0.15)
				(type solid)
			)
			(layer "F.Fab")
		)
		(fp_circle
			(center 0.001 0.001)
			(end 0.297 0.001)
			(stroke
				(width 0.15)
				(type solid)
			)
			(fill no)
			(layer "F.Fab")
		)
		(fp_circle
			(center -0.499 -0.499)
			(end -0.453 -0.499)
			(stroke
				(width 0.15)
				(type solid)
			)
			(fill yes)
			(layer "F.Fab")
		)
		(fp_text user "${REFERENCE}"
			(at 0.2 1.7 180)
			(unlocked yes)
			(layer "F.Fab")
			(effects
				(font
					(size 1 1)
					(thickness 0.15)
				)
			)
		)
		(pad "1" smd roundrect
			(at -0.701 -0.403 180)
			(size 0.5 0.3)
			(layers "F.Cu" "F.Mask" "F.Paste")
			(roundrect_rratio 0.25)
			(net 9 "I2C_1_SDA")
			(pinfunction "SDA")
			(pintype "bidirectional")
		)
		(pad "2" smd roundrect
			(at -0.701 0.401 180)
			(size 0.5 0.3)
			(layers "F.Cu" "F.Mask" "F.Paste")
			(roundrect_rratio 0.25)
			(net 8 "I2C_1_SCL")
			(pinfunction "SCL")
			(pintype "input")
		)
		(pad "3" smd roundrect
			(at 0.699 0.401 180)
			(size 0.5 0.3)
			(layers "F.Cu" "F.Mask" "F.Paste")
			(roundrect_rratio 0.25)
			(net 2 "+3V3")
			(pinfunction "VDD")
			(pintype "power_in")
		)
		(pad "4" smd roundrect
			(at 0.699 -0.403 180)
			(size 0.5 0.3)
			(layers "F.Cu" "F.Mask" "F.Paste")
			(roundrect_rratio 0.25)
			(net 1 "GND")
			(pinfunction "VSS")
			(pintype "power_in")
		)
	)
	(footprint "antmicro-footprints:C_0402_1005Metric"
		(layer "F.Cu")
		(at 195.376 138.397 90)
		(descr "Capacitor SMD 0402")
		(tags "capacitor SMD 0402")
		(property "Reference" "C17"
			(at 17.93 -9.694 270)
			(layer "B.SilkS")
			(effects
				(font
					(size 0.7 0.7)
					(thickness 0.15)
				)
				(justify left bottom mirror)
			)
		)
		(property "Value" "C_100n_0402"
			(at 0 1.4 90)
			(layer "F.Fab")
			(effects
				(font
					(size 0.7 0.7)
					(thickness 0.15)
				)
				(justify left bottom)
			)
		)
		(property "Description" "SMD Multilayer Ceramic Capacitor, 0.1 µF, 50 V, 0402 [1005 Metric], ± 10%, X5R, GRM Series"
			(at 0 0 90)
			(layer "F.Fab")
			(hide yes)
			(effects
				(font
					(size 1.27 1.27)
					(thickness 0.15)
				)
			)
		)
		(property "Author" "Antmicro"
			(at 333.773 -56.979 0)
			(layer "F.Fab")
			(hide yes)
			(effects
				(font
					(size 1 1)
					(thickness 0.15)
				)
			)
		)
		(property "Dielectric" "X5R"
			(at 333.773 -56.979 0)
			(layer "F.Fab")
			(hide yes)
			(effects
				(font
					(size 1 1)
					(thickness 0.15)
				)
			)
		)
		(property "License" "Apache-2.0"
			(at 333.773 -56.979 0)
			(layer "F.Fab")
			(hide yes)
			(effects
				(font
					(size 1 1)
					(thickness 0.15)
				)
			)
		)
		(property "MPN" "GRM155R61H104KE14D"
			(at 333.773 -56.979 0)
			(layer "F.Fab")
			(hide yes)
			(effects
				(font
					(size 1 1)
					(thickness 0.15)
				)
			)
		)
		(property "Manufacturer" "Murata"
			(at 333.773 -56.979 0)
			(layer "F.Fab")
			(hide yes)
			(effects
				(font
					(size 1 1)
					(thickness 0.15)
				)
			)
		)
		(property "Public" "False"
			(at 333.773 -56.979 0)
			(layer "F.Fab")
			(hide yes)
			(effects
				(font
					(size 1 1)
					(thickness 0.15)
				)
			)
		)
		(property "Val" "100n"
			(at 333.773 -56.979 0)
			(layer "F.Fab")
			(hide yes)
			(effects
				(font
					(size 1 1)
					(thickness 0.15)
				)
			)
		)
		(property "Voltage" "50V"
			(at 333.773 -56.979 0)
			(layer "F.Fab")
			(hide yes)
			(effects
				(font
					(size 1 1)
					(thickness 0.15)
				)
			)
		)
		(sheetfile "environment-sensor.kicad_sch")
		(attr smd)
		(fp_rect
			(start -0.925 -0.47)
			(end 0.925 0.47)
			(stroke
				(width 0.05)
				(type default)
			)
			(fill no)
			(layer "F.CrtYd")
		)
		(fp_line
			(start 0.504 -0.25)
			(end 0.504 0.248)
			(stroke
				(width 0.15)
				(type solid)
			)
			(layer "F.Fab")
		)
		(fp_line
			(start -0.494 -0.25)
			(end 0.504 -0.25)
			(stroke
				(width 0.15)
				(type solid)
			)
			(layer "F.Fab")
		)
		(fp_line
			(start 0.504 0.248)
			(end -0.494 0.248)
			(stroke
				(width 0.15)
				(type solid)
			)
			(layer "F.Fab")
		)
		(fp_line
			(start -0.494 0.248)
			(end -0.494 -0.25)
			(stroke
				(width 0.15)
				(type solid)
			)
			(layer "F.Fab")
		)
		(pad "1" smd roundrect
			(at -0.48 0 90)
			(size 0.59 0.64)
			(layers "F.Cu" "F.Mask" "F.Paste")
			(roundrect_rratio 0.25)
			(net 1 "GND")
			(pintype "passive")
		)
		(pad "2" smd roundrect
			(at 0.48 0 90)
			(size 0.59 0.64)
			(layers "F.Cu" "F.Mask" "F.Paste")
			(roundrect_rratio 0.25)
			(net 2 "+3V3")
			(pintype "passive")
		)
	)
)
